(kicad_pcb
	(version 20260206)
	(generator "pcbnew")
	(generator_version "10.0")
	(general
		(thickness 1.6)
		(legacy_teardrops no)
	)
	(paper "A4")
	(title_block
		(title "Bryce Canyon_F.DPB_16315-1-OCP.brd")
		(comment 1 "Bryce Canyon / footprints 2193-2200 of 2223")
	)
	(layers
		(0 "F.Cu" signal "TOP")
		(4 "In1.Cu" signal "L2GND")
		(6 "In2.Cu" signal "L3")
		(8 "In3.Cu" signal "L4GND")
		(10 "In4.Cu" signal "L5")
		(12 "In5.Cu" signal "L6VCC")
		(14 "In6.Cu" signal "L7VCC")
		(16 "In7.Cu" signal "L8")
		(18 "In8.Cu" signal "L9GND")
		(20 "In9.Cu" signal "L10")
		(22 "In10.Cu" signal "L11GND")
		(2 "B.Cu" signal "BOTTOM")
		(9 "F.Adhes" user "F.Adhesive")
		(11 "B.Adhes" user "B.Adhesive")
		(13 "F.Paste" user "Package Geometry/Pastemask Top")
		(15 "B.Paste" user "Package Geometry/Pastemask Bottom")
		(5 "F.SilkS" user "Ref Des/Silkscreen Top")
		(7 "B.SilkS" user "Ref Des/Silkscreen Bottom")
		(1 "F.Mask" user "Board Geometry/Soldermask Top")
		(3 "B.Mask" user "Board Geometry/Soldermask Bottom")
		(17 "Dwgs.User" user "User.Drawings")
		(19 "Cmts.User" user "User.Comments")
		(21 "Eco1.User" user "User.Eco1")
		(23 "Eco2.User" user "User.Eco2")
		(25 "Edge.Cuts" user "Board Geometry/Outline")
		(27 "Margin" user)
		(31 "F.CrtYd" user "Package Geometry/Place Bound Top")
		(29 "B.CrtYd" user "Package Geometry/Place Bound Bottom")
		(35 "F.Fab" user "Ref Des/Assembly Top")
		(33 "B.Fab" user "Ref Des/Assembly Bottom")
	)
	(footprint ""
		(layer "B.Cu")
		(at 440.237372 -252.381766 180)
		(property "Reference" "C634"
			(at 0 0 0)
			(layer "B.SilkS")
			(hide yes)
			(effects
				(font
					(size 1.27 1.27)
				)
				(justify mirror)
			)
		)
		(property "Value" "SCD1U16V2KX-3GP"
			(at -1.1811 -2.7051 180)
			(unlocked yes)
			(layer "B.Fab")
			(hide yes)
			(effects
				(font
					(size 1.016 1.016)
					(thickness 0.1524)
				)
				(justify mirror)
			)
		)
		(property "Device Type" "C402H22"
			(at -1.1811 -4.2291 180)
			(unlocked yes)
			(layer "B.Fab")
			(hide yes)
			(effects
				(font
					(size 1.016 1.016)
					(thickness 0.1524)
				)
				(justify mirror)
			)
		)
		(duplicate_pad_numbers_are_jumpers no)
		(fp_rect
			(start 0.4318 0.9525)
			(end -0.4318 -0.9525)
			(stroke
				(width 0)
				(type default)
			)
			(fill no)
			(layer "B.CrtYd")
		)
		(fp_rect
			(start 0.4318 0.9525)
			(end -0.4318 -0.9525)
			(stroke
				(width 0)
				(type default)
			)
			(fill no)
			(layer "B.Fab")
		)
		(pad "1" smd custom
			(at 0 -0.4445)
			(size 0.1524 0.1524)
			(layers "B.Cu" "B.Mask" "B.Paste")
			(net "P12V_A_VIN_U22")
			(options
				(clearance outline)
				(anchor circle)
			)
			(primitives
				(gr_poly
					(pts
						(arc
							(start 0.3048 0.2032)
							(mid 0.275042 0.275042)
							(end 0.2032 0.3048)
						)
						(arc
							(start -0.2032 0.3048)
							(mid -0.275042 0.275042)
							(end -0.3048 0.2032)
						)
						(arc
							(start -0.3048 -0.2032)
							(mid -0.275042 -0.275042)
							(end -0.2032 -0.3048)
						)
						(arc
							(start 0.2032 -0.3048)
							(mid 0.275042 -0.275042)
							(end 0.3048 -0.2032)
						)
					)
					(width 0)
					(fill yes)
				)
			)
		)
		(pad "2" smd custom
			(at 0 0.4445)
			(size 0.1524 0.1524)
			(layers "B.Cu" "B.Mask" "B.Paste")
			(net "GND")
			(options
				(clearance outline)
				(anchor circle)
			)
			(primitives
				(gr_poly
					(pts
						(arc
							(start 0.3048 0.2032)
							(mid 0.275042 0.275042)
							(end 0.2032 0.3048)
						)
						(arc
							(start -0.2032 0.3048)
							(mid -0.275042 0.275042)
							(end -0.3048 0.2032)
						)
						(arc
							(start -0.3048 -0.2032)
							(mid -0.275042 -0.275042)
							(end -0.2032 -0.3048)
						)
						(arc
							(start 0.2032 -0.3048)
							(mid 0.275042 -0.275042)
							(end 0.3048 -0.2032)
						)
					)
					(width 0)
					(fill yes)
				)
			)
		)
	)
	(footprint ""
		(layer "B.Cu")
		(at 218.9226 -123.4694 180)
		(property "Reference" "R349"
			(at 0 0 0)
			(layer "B.SilkS")
			(hide yes)
			(effects
				(font
					(size 1.27 1.27)
				)
				(justify mirror)
			)
		)
		(property "Value" "0R2J-2-GP"
			(at -0.064008 -3.993896 180)
			(unlocked yes)
			(layer "B.Fab")
			(hide yes)
			(effects
				(font
					(size 1.016 1.016)
					(thickness 0.1524)
				)
				(justify mirror)
			)
		)
		(property "Device Type" "R402H16"
			(at -0.064008 -5.517896 180)
			(unlocked yes)
			(layer "B.Fab")
			(hide yes)
			(effects
				(font
					(size 1.016 1.016)
					(thickness 0.1524)
				)
				(justify mirror)
			)
		)
		(duplicate_pad_numbers_are_jumpers no)
		(fp_line
			(start 0.508 -0.9398)
			(end 0.508 0.9398)
			(stroke
				(width 0.1524)
				(type default)
			)
			(layer "B.SilkS")
		)
		(fp_line
			(start -0.508 -0.9398)
			(end 0.508 -0.9398)
			(stroke
				(width 0.1524)
				(type default)
			)
			(layer "B.SilkS")
		)
		(fp_rect
			(start 0.508 0.9398)
			(end -0.508 -0.9398)
			(stroke
				(width 0)
				(type default)
			)
			(fill no)
			(layer "B.CrtYd")
		)
		(fp_rect
			(start 0.508 0.9398)
			(end -0.508 -0.9398)
			(stroke
				(width 0)
				(type default)
			)
			(fill no)
			(layer "B.Fab")
		)
		(pad "1" smd custom
			(at 0 -0.4445)
			(size 0.1397 0.1397)
			(layers "B.Cu" "B.Mask" "B.Paste")
			(net "I2C_BMC_A_COMP_A_SCL")
			(options
				(clearance outline)
				(anchor circle)
			)
			(primitives
				(gr_poly
					(pts
						(arc
							(start -0.1778 0.2794)
							(mid -0.249642 0.249642)
							(end -0.2794 0.1778)
						)
						(arc
							(start -0.2794 -0.1778)
							(mid -0.249642 -0.249642)
							(end -0.1778 -0.2794)
						)
						(arc
							(start 0.1778 -0.2794)
							(mid 0.249642 -0.249642)
							(end 0.2794 -0.1778)
						)
						(arc
							(start 0.2794 0.1778)
							(mid 0.249642 0.249642)
							(end 0.1778 0.2794)
						)
					)
					(width 0)
					(fill yes)
				)
			)
		)
		(pad "2" smd custom
			(at 0 0.4445)
			(size 0.1397 0.1397)
			(layers "B.Cu" "B.Mask" "B.Paste")
			(net "I2C_BMC_A_COMP_A_SCL_R")
			(options
				(clearance outline)
				(anchor circle)
			)
			(primitives
				(gr_poly
					(pts
						(arc
							(start -0.1778 0.2794)
							(mid -0.249642 0.249642)
							(end -0.2794 0.1778)
						)
						(arc
							(start -0.2794 -0.1778)
							(mid -0.249642 -0.249642)
							(end -0.1778 -0.2794)
						)
						(arc
							(start 0.1778 -0.2794)
							(mid 0.249642 -0.249642)
							(end 0.2794 -0.1778)
						)
						(arc
							(start 0.2794 0.1778)
							(mid 0.249642 0.249642)
							(end 0.1778 0.2794)
						)
					)
					(width 0)
					(fill yes)
				)
			)
		)
	)
	(footprint ""
		(layer "B.Cu")
		(at 478.7265 -223.602042 90)
		(property "Reference" "R1268"
			(at 0 0 90)
			(layer "B.SilkS")
			(hide yes)
			(effects
				(font
					(size 1.27 1.27)
				)
				(justify mirror)
			)
		)
		(property "Value" "2K7R2F-GP"
			(at -0.064008 -3.993896 90)
			(unlocked yes)
			(layer "B.Fab")
			(hide yes)
			(effects
				(font
					(size 1.016 1.016)
					(thickness 0.1524)
				)
				(justify mirror)
			)
		)
		(property "Device Type" "R402H16"
			(at -0.064008 -5.517896 90)
			(unlocked yes)
			(layer "B.Fab")
			(hide yes)
			(effects
				(font
					(size 1.016 1.016)
					(thickness 0.1524)
				)
				(justify mirror)
			)
		)
		(duplicate_pad_numbers_are_jumpers no)
		(fp_line
			(start 0.508 -0.9398)
			(end 0.508 0.9398)
			(stroke
				(width 0.1524)
				(type default)
			)
			(layer "B.SilkS")
		)
		(fp_line
			(start -0.508 -0.9398)
			(end 0.508 -0.9398)
			(stroke
				(width 0.1524)
				(type default)
			)
			(layer "B.SilkS")
		)
		(fp_rect
			(start 0.508 0.9398)
			(end -0.508 -0.9398)
			(stroke
				(width 0)
				(type default)
			)
			(fill no)
			(layer "B.CrtYd")
		)
		(fp_rect
			(start 0.508 0.9398)
			(end -0.508 -0.9398)
			(stroke
				(width 0)
				(type default)
			)
			(fill no)
			(layer "B.Fab")
		)
		(pad "1" smd custom
			(at 0 -0.4445 270)
			(size 0.1397 0.1397)
			(layers "B.Cu" "B.Mask" "B.Paste")
			(net "P5V_D_LL")
			(options
				(clearance outline)
				(anchor circle)
			)
			(primitives
				(gr_poly
					(pts
						(arc
							(start -0.1778 0.2794)
							(mid -0.249642 0.249642)
							(end -0.2794 0.1778)
						)
						(arc
							(start -0.2794 -0.1778)
							(mid -0.249642 -0.249642)
							(end -0.1778 -0.2794)
						)
						(arc
							(start 0.1778 -0.2794)
							(mid 0.249642 -0.249642)
							(end 0.2794 -0.1778)
						)
						(arc
							(start 0.2794 0.1778)
							(mid 0.249642 0.249642)
							(end 0.1778 0.2794)
						)
					)
					(width 0)
					(fill yes)
				)
			)
		)
		(pad "2" smd custom
			(at 0 0.4445 270)
			(size 0.1397 0.1397)
			(layers "B.Cu" "B.Mask" "B.Paste")
			(net "P5V_D_LL_R")
			(options
				(clearance outline)
				(anchor circle)
			)
			(primitives
				(gr_poly
					(pts
						(arc
							(start -0.1778 0.2794)
							(mid -0.249642 0.249642)
							(end -0.2794 0.1778)
						)
						(arc
							(start -0.2794 -0.1778)
							(mid -0.249642 -0.249642)
							(end -0.1778 -0.2794)
						)
						(arc
							(start 0.1778 -0.2794)
							(mid 0.249642 -0.249642)
							(end 0.2794 -0.1778)
						)
						(arc
							(start 0.2794 0.1778)
							(mid 0.249642 0.249642)
							(end 0.1778 0.2794)
						)
					)
					(width 0)
					(fill yes)
				)
			)
		)
	)
	(footprint ""
		(layer "B.Cu")
		(at 189.377828 -238.277908 90)
		(property "Reference" "C682"
			(at 0 0 90)
			(layer "B.SilkS")
			(hide yes)
			(effects
				(font
					(size 1.27 1.27)
				)
				(justify mirror)
			)
		)
		(property "Value" "SC10U6D3V5KX-4GP"
			(at 0.0762 -6.1214 90)
			(unlocked yes)
			(layer "B.Fab")
			(hide yes)
			(effects
				(font
					(size 1.016 1.016)
					(thickness 0.1524)
				)
				(justify mirror)
			)
		)
		(property "Device Type" "C805H58"
			(at 0.0762 -8.1534 90)
			(unlocked yes)
			(layer "B.Fab")
			(hide yes)
			(effects
				(font
					(size 1.016 1.016)
					(thickness 0.1524)
				)
				(justify mirror)
			)
		)
		(duplicate_pad_numbers_are_jumpers no)
		(fp_line
			(start -0.635 0)
			(end 0.635 0)
			(stroke
				(width 0.508)
				(type default)
			)
			(layer "B.SilkS")
		)
		(fp_rect
			(start 0.9652 1.778)
			(end -0.9652 -1.778)
			(stroke
				(width 0)
				(type default)
			)
			(fill no)
			(layer "B.CrtYd")
		)
		(fp_poly
			(pts
				(xy 0.9652 -1.778) (xy -0.9652 -1.778) (xy -0.9652 1.778) (xy 0.9652 1.778)
			)
			(stroke
				(width 0)
				(type default)
			)
			(fill no)
			(layer "B.Fab")
		)
		(pad "1" smd rect
			(at 0 -0.9652 270)
			(size 1.397 1.143)
			(layers "B.Cu" "B.Mask" "B.Paste")
			(net "P3V3_STBY_A")
		)
		(pad "2" smd rect
			(at 0 0.9652 270)
			(size 1.397 1.143)
			(layers "B.Cu" "B.Mask" "B.Paste")
			(net "GND")
		)
	)
	(footprint ""
		(layer "B.Cu")
		(at 469.646 -230.505 -90)
		(property "Reference" "C657"
			(at 0 0 90)
			(layer "B.SilkS")
			(hide yes)
			(effects
				(font
					(size 1.27 1.27)
				)
				(justify mirror)
			)
		)
		(property "Value" "SC2200P50V2KX-2GP"
			(at -1.1811 -2.7051 270)
			(unlocked yes)
			(layer "B.Fab")
			(hide yes)
			(effects
				(font
					(size 1.016 1.016)
					(thickness 0.1524)
				)
				(justify mirror)
			)
		)
		(property "Device Type" "C402H22"
			(at -1.1811 -4.2291 270)
			(unlocked yes)
			(layer "B.Fab")
			(hide yes)
			(effects
				(font
					(size 1.016 1.016)
					(thickness 0.1524)
				)
				(justify mirror)
			)
		)
		(duplicate_pad_numbers_are_jumpers no)
		(fp_rect
			(start 0.4318 0.9525)
			(end -0.4318 -0.9525)
			(stroke
				(width 0)
				(type default)
			)
			(fill no)
			(layer "B.CrtYd")
		)
		(fp_rect
			(start 0.4318 0.9525)
			(end -0.4318 -0.9525)
			(stroke
				(width 0)
				(type default)
			)
			(fill no)
			(layer "B.Fab")
		)
		(pad "1" smd custom
			(at 0 -0.4445 90)
			(size 0.1524 0.1524)
			(layers "B.Cu" "B.Mask" "B.Paste")
			(net "P5V_D_LL")
			(options
				(clearance outline)
				(anchor circle)
			)
			(primitives
				(gr_poly
					(pts
						(arc
							(start 0.3048 0.2032)
							(mid 0.275042 0.275042)
							(end 0.2032 0.3048)
						)
						(arc
							(start -0.2032 0.3048)
							(mid -0.275042 0.275042)
							(end -0.3048 0.2032)
						)
						(arc
							(start -0.3048 -0.2032)
							(mid -0.275042 -0.275042)
							(end -0.2032 -0.3048)
						)
						(arc
							(start 0.2032 -0.3048)
							(mid 0.275042 -0.275042)
							(end 0.3048 -0.2032)
						)
					)
					(width 0)
					(fill yes)
				)
			)
		)
		(pad "2" smd custom
			(at 0 0.4445 90)
			(size 0.1524 0.1524)
			(layers "B.Cu" "B.Mask" "B.Paste")
			(net "P5V_D_SNB")
			(options
				(clearance outline)
				(anchor circle)
			)
			(primitives
				(gr_poly
					(pts
						(arc
							(start 0.3048 0.2032)
							(mid 0.275042 0.275042)
							(end 0.2032 0.3048)
						)
						(arc
							(start -0.2032 0.3048)
							(mid -0.275042 0.275042)
							(end -0.3048 0.2032)
						)
						(arc
							(start -0.3048 -0.2032)
							(mid -0.275042 -0.275042)
							(end -0.2032 -0.3048)
						)
						(arc
							(start 0.2032 -0.3048)
							(mid 0.275042 -0.275042)
							(end 0.3048 -0.2032)
						)
					)
					(width 0)
					(fill yes)
				)
			)
		)
	)
	(footprint ""
		(layer "B.Cu")
		(at 39.0652 -142.1384 180)
		(property "Reference" "C616"
			(at 0 0 0)
			(layer "B.SilkS")
			(hide yes)
			(effects
				(font
					(size 1.27 1.27)
				)
				(justify mirror)
			)
		)
		(property "Value" "SC10U16V5KX-7-GP-U"
			(at 0.0762 -6.1214 180)
			(unlocked yes)
			(layer "B.Fab")
			(hide yes)
			(effects
				(font
					(size 1.016 1.016)
					(thickness 0.1524)
				)
				(justify mirror)
			)
		)
		(property "Device Type" "C805H58"
			(at 0.0762 -8.1534 180)
			(unlocked yes)
			(layer "B.Fab")
			(hide yes)
			(effects
				(font
					(size 1.016 1.016)
					(thickness 0.1524)
				)
				(justify mirror)
			)
		)
		(duplicate_pad_numbers_are_jumpers no)
		(fp_line
			(start -0.635 0)
			(end 0.635 0)
			(stroke
				(width 0.508)
				(type default)
			)
			(layer "B.SilkS")
		)
		(fp_rect
			(start 0.9652 1.778)
			(end -0.9652 -1.778)
			(stroke
				(width 0)
				(type default)
			)
			(fill no)
			(layer "B.CrtYd")
		)
		(fp_poly
			(pts
				(xy 0.9652 -1.778) (xy -0.9652 -1.778) (xy -0.9652 1.778) (xy 0.9652 1.778)
			)
			(stroke
				(width 0)
				(type default)
			)
			(fill no)
			(layer "B.Fab")
		)
		(pad "1" smd rect
			(at 0 -0.9652)
			(size 1.397 1.143)
			(layers "B.Cu" "B.Mask" "B.Paste")
			(net "P12V_A_VIN_U21")
		)
		(pad "2" smd rect
			(at 0 0.9652)
			(size 1.397 1.143)
			(layers "B.Cu" "B.Mask" "B.Paste")
			(net "GND")
		)
	)
	(footprint ""
		(layer "B.Cu")
		(at 439.846974 -256.172716 -90)
		(property "Reference" "C639"
			(at 0 0 90)
			(layer "B.SilkS")
			(hide yes)
			(effects
				(font
					(size 1.27 1.27)
				)
				(justify mirror)
			)
		)
		(property "Value" "SC4D7U25V5KX-GP"
			(at 0.0762 -6.1214 270)
			(unlocked yes)
			(layer "B.Fab")
			(hide yes)
			(effects
				(font
					(size 1.016 1.016)
					(thickness 0.1524)
				)
				(justify mirror)
			)
		)
		(property "Device Type" "C805H54"
			(at 0.0762 -8.1534 270)
			(unlocked yes)
			(layer "B.Fab")
			(hide yes)
			(effects
				(font
					(size 1.016 1.016)
					(thickness 0.1524)
				)
				(justify mirror)
			)
		)
		(duplicate_pad_numbers_are_jumpers no)
		(fp_line
			(start -0.635 0)
			(end 0.635 0)
			(stroke
				(width 0.508)
				(type default)
			)
			(layer "B.SilkS")
		)
		(fp_rect
			(start 0.9652 1.778)
			(end -0.9652 -1.778)
			(stroke
				(width 0)
				(type default)
			)
			(fill no)
			(layer "B.CrtYd")
		)
		(fp_poly
			(pts
				(xy 0.9652 -1.778) (xy -0.9652 -1.778) (xy -0.9652 1.778) (xy 0.9652 1.778)
			)
			(stroke
				(width 0)
				(type default)
			)
			(fill no)
			(layer "B.Fab")
		)
		(pad "1" smd rect
			(at 0 -0.9652 90)
			(size 1.397 1.143)
			(layers "B.Cu" "B.Mask" "B.Paste")
			(net "P12V_A_VDD_U22")
		)
		(pad "2" smd rect
			(at 0 0.9652 90)
			(size 1.397 1.143)
			(layers "B.Cu" "B.Mask" "B.Paste")
			(net "GND")
		)
	)
	(footprint ""
		(layer "B.Cu")
		(at 222.1992 -118.2878)
		(property "Reference" "C3"
			(at 0 0 0)
			(layer "B.SilkS")
			(hide yes)
			(effects
				(font
					(size 1.27 1.27)
				)
				(justify mirror)
			)
		)
		(property "Value" "SCD1U16V2KX-3GP"
			(at -1.1811 -2.7051 0)
			(unlocked yes)
			(layer "B.Fab")
			(hide yes)
			(effects
				(font
					(size 1.016 1.016)
					(thickness 0.1524)
				)
				(justify mirror)
			)
		)
		(property "Device Type" "C402H22"
			(at -1.1811 -4.2291 0)
			(unlocked yes)
			(layer "B.Fab")
			(hide yes)
			(effects
				(font
					(size 1.016 1.016)
					(thickness 0.1524)
				)
				(justify mirror)
			)
		)
		(duplicate_pad_numbers_are_jumpers no)
		(fp_rect
			(start 0.4318 0.9525)
			(end -0.4318 -0.9525)
			(stroke
				(width 0)
				(type default)
			)
			(fill no)
			(layer "B.CrtYd")
		)
		(fp_rect
			(start 0.4318 0.9525)
			(end -0.4318 -0.9525)
			(stroke
				(width 0)
				(type default)
			)
			(fill no)
			(layer "B.Fab")
		)
		(pad "1" smd custom
			(at 0 -0.4445 180)
			(size 0.1524 0.1524)
			(layers "B.Cu" "B.Mask" "B.Paste")
			(net "P3V3_STBY_A")
			(options
				(clearance outline)
				(anchor circle)
			)
			(primitives
				(gr_poly
					(pts
						(arc
							(start 0.3048 0.2032)
							(mid 0.275042 0.275042)
							(end 0.2032 0.3048)
						)
						(arc
							(start -0.2032 0.3048)
							(mid -0.275042 0.275042)
							(end -0.3048 0.2032)
						)
						(arc
							(start -0.3048 -0.2032)
							(mid -0.275042 -0.275042)
							(end -0.2032 -0.3048)
						)
						(arc
							(start 0.2032 -0.3048)
							(mid 0.275042 -0.275042)
							(end 0.3048 -0.2032)
						)
					)
					(width 0)
					(fill yes)
				)
			)
		)
		(pad "2" smd custom
			(at 0 0.4445 180)
			(size 0.1524 0.1524)
			(layers "B.Cu" "B.Mask" "B.Paste")
			(net "GND")
			(options
				(clearance outline)
				(anchor circle)
			)
			(primitives
				(gr_poly
					(pts
						(arc
							(start 0.3048 0.2032)
							(mid 0.275042 0.275042)
							(end 0.2032 0.3048)
						)
						(arc
							(start -0.2032 0.3048)
							(mid -0.275042 0.275042)
							(end -0.3048 0.2032)
						)
						(arc
							(start -0.3048 -0.2032)
							(mid -0.275042 -0.275042)
							(end -0.2032 -0.3048)
						)
						(arc
							(start 0.2032 -0.3048)
							(mid 0.275042 -0.275042)
							(end 0.3048 -0.2032)
						)
					)
					(width 0)
					(fill yes)
				)
			)
		)
	)
)
